(kicad_pcb
	(version 20260206)
	(generator "pcbnew")
	(generator_version "10.0")
	(general
		(thickness 1.6)
		(legacy_teardrops no)
	)
	(paper "A4")
	(title_block
		(title "dpb — 14545-sa.0730WZS0815.brd")
		(comment 1 "Honey Badger (Wiwynn) / footprints 956-963 of 1066")
	)
	(layers
		(0 "F.Cu" signal "TOP")
		(4 "In1.Cu" signal "L2GND")
		(6 "In2.Cu" signal "L3")
		(8 "In3.Cu" signal "L4VCC")
		(10 "In4.Cu" signal "L5VCC")
		(12 "In5.Cu" signal "L6")
		(14 "In6.Cu" signal "L7GND")
		(2 "B.Cu" signal "BOTTOM")
		(9 "F.Adhes" user "F.Adhesive")
		(11 "B.Adhes" user "B.Adhesive")
		(13 "F.Paste" user "Package Geometry/Pastemask Top")
		(15 "B.Paste" user "Package Geometry/Pastemask Bottom")
		(5 "F.SilkS" user "Ref Des/Silkscreen Top")
		(7 "B.SilkS" user "Ref Des/Silkscreen Bottom")
		(1 "F.Mask" user "Board Geometry/Soldermask Top")
		(3 "B.Mask" user "Board Geometry/Soldermask Bottom")
		(17 "Dwgs.User" user "User.Drawings")
		(19 "Cmts.User" user "User.Comments")
		(21 "Eco1.User" user "User.Eco1")
		(23 "Eco2.User" user "User.Eco2")
		(25 "Edge.Cuts" user "Board Geometry/Outline")
		(27 "Margin" user)
		(31 "F.CrtYd" user "Package Geometry/Place Bound Top")
		(29 "B.CrtYd" user "Package Geometry/Place Bound Bottom")
		(35 "F.Fab" user "Ref Des/Assembly Top")
		(33 "B.Fab" user "Ref Des/Assembly Bottom")
	)
	(footprint ""
		(layer "F.Cu")
		(at 26.288746 -441.8457 90)
		(property "Reference" "C265"
			(at 0 0 90)
			(layer "F.SilkS")
			(hide yes)
			(effects
				(font
					(size 1.27 1.27)
				)
			)
		)
		(property "Value" "SCD01U50V2KX-1GP"
			(at 1.1811 -2.7051 90)
			(unlocked yes)
			(layer "F.Fab")
			(hide yes)
			(effects
				(font
					(size 1.016 1.016)
					(thickness 0.1524)
				)
			)
		)
		(property "Device Type" "C402H22"
			(at 1.1811 -4.2291 90)
			(unlocked yes)
			(layer "F.Fab")
			(hide yes)
			(effects
				(font
					(size 1.016 1.016)
					(thickness 0.1524)
				)
			)
		)
		(duplicate_pad_numbers_are_jumpers no)
		(fp_rect
			(start -0.4318 0.9525)
			(end 0.4318 -0.9525)
			(stroke
				(width 0)
				(type default)
			)
			(fill no)
			(layer "F.CrtYd")
		)
		(fp_rect
			(start -0.4318 0.9525)
			(end 0.4318 -0.9525)
			(stroke
				(width 0)
				(type default)
			)
			(fill no)
			(layer "F.Fab")
		)
		(pad "1" smd custom
			(at 0 -0.4445 90)
			(size 0.1524 0.1524)
			(layers "F.Cu" "F.Mask" "F.Paste")
			(net "SAS2X28_DRIVE_RX_P_B10")
			(options
				(clearance outline)
				(anchor circle)
			)
			(primitives
				(gr_poly
					(pts
						(arc
							(start 0.3048 -0.2032)
							(mid 0.275042 -0.275042)
							(end 0.2032 -0.3048)
						)
						(arc
							(start -0.2032 -0.3048)
							(mid -0.275042 -0.275042)
							(end -0.3048 -0.2032)
						)
						(arc
							(start -0.3048 0.2032)
							(mid -0.275042 0.275042)
							(end -0.2032 0.3048)
						)
						(arc
							(start 0.2032 0.3048)
							(mid 0.275042 0.275042)
							(end 0.3048 0.2032)
						)
					)
					(width 0)
					(fill yes)
				)
			)
		)
		(pad "2" smd custom
			(at 0 0.4445 90)
			(size 0.1524 0.1524)
			(layers "F.Cu" "F.Mask" "F.Paste")
			(net "SAS2X28_B_HDD10_RX_+")
			(options
				(clearance outline)
				(anchor circle)
			)
			(primitives
				(gr_poly
					(pts
						(arc
							(start 0.3048 -0.2032)
							(mid 0.275042 -0.275042)
							(end 0.2032 -0.3048)
						)
						(arc
							(start -0.2032 -0.3048)
							(mid -0.275042 -0.275042)
							(end -0.3048 -0.2032)
						)
						(arc
							(start -0.3048 0.2032)
							(mid -0.275042 0.275042)
							(end -0.2032 0.3048)
						)
						(arc
							(start 0.2032 0.3048)
							(mid 0.275042 0.275042)
							(end 0.3048 0.2032)
						)
					)
					(width 0)
					(fill yes)
				)
			)
		)
	)
	(footprint ""
		(layer "F.Cu")
		(at 194.818 -293.878)
		(property "Reference" "C381"
			(at 0 0 0)
			(layer "F.SilkS")
			(hide yes)
			(effects
				(font
					(size 1.27 1.27)
				)
			)
		)
		(property "Value" "SCD033U25V2KX-GP"
			(at 1.1811 -2.7051 0)
			(unlocked yes)
			(layer "F.Fab")
			(hide yes)
			(effects
				(font
					(size 1.016 1.016)
					(thickness 0.1524)
				)
			)
		)
		(property "Device Type" "C402H22"
			(at 1.1811 -4.2291 0)
			(unlocked yes)
			(layer "F.Fab")
			(hide yes)
			(effects
				(font
					(size 1.016 1.016)
					(thickness 0.1524)
				)
			)
		)
		(duplicate_pad_numbers_are_jumpers no)
		(fp_rect
			(start -0.4318 0.9525)
			(end 0.4318 -0.9525)
			(stroke
				(width 0)
				(type default)
			)
			(fill no)
			(layer "F.CrtYd")
		)
		(fp_rect
			(start -0.4318 0.9525)
			(end 0.4318 -0.9525)
			(stroke
				(width 0)
				(type default)
			)
			(fill no)
			(layer "F.Fab")
		)
		(pad "1" smd custom
			(at 0 -0.4445)
			(size 0.1524 0.1524)
			(layers "F.Cu" "F.Mask" "F.Paste")
			(net "P12V")
			(options
				(clearance outline)
				(anchor circle)
			)
			(primitives
				(gr_poly
					(pts
						(arc
							(start 0.3048 -0.2032)
							(mid 0.275042 -0.275042)
							(end 0.2032 -0.3048)
						)
						(arc
							(start -0.2032 -0.3048)
							(mid -0.275042 -0.275042)
							(end -0.3048 -0.2032)
						)
						(arc
							(start -0.3048 0.2032)
							(mid -0.275042 0.275042)
							(end -0.2032 0.3048)
						)
						(arc
							(start 0.2032 0.3048)
							(mid 0.275042 0.275042)
							(end 0.3048 0.2032)
						)
					)
					(width 0)
					(fill yes)
				)
			)
		)
		(pad "2" smd custom
			(at 0 0.4445)
			(size 0.1524 0.1524)
			(layers "F.Cu" "F.Mask" "F.Paste")
			(net "SW_HDD2_N")
			(options
				(clearance outline)
				(anchor circle)
			)
			(primitives
				(gr_poly
					(pts
						(arc
							(start 0.3048 -0.2032)
							(mid 0.275042 -0.275042)
							(end 0.2032 -0.3048)
						)
						(arc
							(start -0.2032 -0.3048)
							(mid -0.275042 -0.275042)
							(end -0.3048 -0.2032)
						)
						(arc
							(start -0.3048 0.2032)
							(mid -0.275042 0.275042)
							(end -0.2032 0.3048)
						)
						(arc
							(start 0.2032 0.3048)
							(mid 0.275042 0.275042)
							(end 0.3048 0.2032)
						)
					)
					(width 0)
					(fill yes)
				)
			)
		)
	)
	(footprint ""
		(layer "F.Cu")
		(at 35.432746 -124.869702)
		(property "Reference" "C316"
			(at 0 0 0)
			(layer "F.SilkS")
			(hide yes)
			(effects
				(font
					(size 1.27 1.27)
				)
			)
		)
		(property "Value" "SC1U16V3KX-5GP"
			(at 0 -2.8194 0)
			(unlocked yes)
			(layer "F.Fab")
			(hide yes)
			(effects
				(font
					(size 1.016 1.016)
					(thickness 0.1524)
				)
			)
		)
		(property "Device Type" "C603H36"
			(at 0 -4.3434 0)
			(unlocked yes)
			(layer "F.Fab")
			(hide yes)
			(effects
				(font
					(size 1.016 1.016)
					(thickness 0.1524)
				)
			)
		)
		(duplicate_pad_numbers_are_jumpers no)
		(fp_line
			(start 0.508 0)
			(end -0.508 0)
			(stroke
				(width 0.2032)
				(type default)
			)
			(layer "F.SilkS")
		)
		(fp_rect
			(start -0.5842 1.3335)
			(end 0.5842 -1.3335)
			(stroke
				(width 0)
				(type default)
			)
			(fill no)
			(layer "F.CrtYd")
		)
		(fp_rect
			(start -0.5842 1.3335)
			(end 0.5842 -1.3335)
			(stroke
				(width 0)
				(type default)
			)
			(fill no)
			(layer "F.Fab")
		)
		(pad "1" smd custom
			(at 0 -0.762)
			(size 0.2159 0.2159)
			(layers "F.Cu" "F.Mask" "F.Paste")
			(net "P5V_HDD13")
			(options
				(clearance outline)
				(anchor circle)
			)
			(primitives
				(gr_poly
					(pts
						(arc
							(start -0.3302 -0.4318)
							(mid -0.402042 -0.402042)
							(end -0.4318 -0.3302)
						)
						(arc
							(start -0.4318 0.3302)
							(mid -0.402042 0.402042)
							(end -0.3302 0.4318)
						)
						(arc
							(start 0.3302 0.4318)
							(mid 0.402042 0.402042)
							(end 0.4318 0.3302)
						)
						(arc
							(start 0.4318 -0.3302)
							(mid 0.402042 -0.402042)
							(end 0.3302 -0.4318)
						)
					)
					(width 0)
					(fill yes)
				)
			)
		)
		(pad "2" smd custom
			(at 0 0.762)
			(size 0.2159 0.2159)
			(layers "F.Cu" "F.Mask" "F.Paste")
			(net "GND")
			(options
				(clearance outline)
				(anchor circle)
			)
			(primitives
				(gr_poly
					(pts
						(arc
							(start -0.3302 -0.4318)
							(mid -0.402042 -0.402042)
							(end -0.4318 -0.3302)
						)
						(arc
							(start -0.4318 0.3302)
							(mid -0.402042 0.402042)
							(end -0.3302 0.4318)
						)
						(arc
							(start 0.3302 0.4318)
							(mid 0.402042 0.402042)
							(end 0.4318 0.3302)
						)
						(arc
							(start 0.4318 -0.3302)
							(mid 0.402042 -0.402042)
							(end 0.3302 -0.4318)
						)
					)
					(width 0)
					(fill yes)
				)
			)
		)
	)
	(footprint ""
		(layer "F.Cu")
		(at 213.054184 -188.488828 180)
		(property "Reference" "C160"
			(at 0 0 180)
			(layer "F.SilkS")
			(hide yes)
			(effects
				(font
					(size 1.27 1.27)
				)
			)
		)
		(property "Value" "SC10U25V6KX-1GP"
			(at -0.0762 -5.1308 180)
			(unlocked yes)
			(layer "F.Fab")
			(hide yes)
			(effects
				(font
					(size 1.016 1.016)
					(thickness 0.1524)
				)
			)
		)
		(property "Device Type" "C1206H71"
			(at -0.127 -6.6548 180)
			(unlocked yes)
			(layer "F.Fab")
			(hide yes)
			(effects
				(font
					(size 1.016 1.016)
					(thickness 0.1524)
				)
			)
		)
		(duplicate_pad_numbers_are_jumpers no)
		(fp_line
			(start 1.016 2.2352)
			(end -1.016 2.2352)
			(stroke
				(width 0.1524)
				(type default)
			)
			(layer "F.SilkS")
		)
		(fp_line
			(start 1.016 0.8382)
			(end 1.016 2.2352)
			(stroke
				(width 0.1524)
				(type default)
			)
			(layer "F.SilkS")
		)
		(fp_line
			(start 1.016 -2.2352)
			(end 1.016 -0.8382)
			(stroke
				(width 0.1524)
				(type default)
			)
			(layer "F.SilkS")
		)
		(fp_line
			(start -1.016 2.2352)
			(end -1.016 0.8382)
			(stroke
				(width 0.1524)
				(type default)
			)
			(layer "F.SilkS")
		)
		(fp_line
			(start -1.016 -0.8382)
			(end -1.016 -2.2352)
			(stroke
				(width 0.1524)
				(type default)
			)
			(layer "F.SilkS")
		)
		(fp_line
			(start -1.016 -2.2352)
			(end 1.016 -2.2352)
			(stroke
				(width 0.1524)
				(type default)
			)
			(layer "F.SilkS")
		)
		(fp_rect
			(start -1.0922 2.3114)
			(end 1.0922 -2.3114)
			(stroke
				(width 0)
				(type default)
			)
			(fill no)
			(layer "F.CrtYd")
		)
		(fp_poly
			(pts
				(xy 1.0922 -2.3114) (xy 1.0922 2.3114) (xy -1.0922 2.3114) (xy -1.0922 -2.3114)
			)
			(stroke
				(width 0)
				(type default)
			)
			(fill no)
			(layer "F.Fab")
		)
		(pad "1" smd rect
			(at 0 -1.397 180)
			(size 1.651 1.27)
			(layers "F.Cu" "F.Mask" "F.Paste")
			(net "P12V_HDD3")
		)
		(pad "2" smd rect
			(at 0 1.397 180)
			(size 1.651 1.27)
			(layers "F.Cu" "F.Mask" "F.Paste")
			(net "GND")
		)
	)
	(footprint ""
		(layer "F.Cu")
		(at 211.792058 -388.441184)
		(property "Reference" "C126"
			(at 0 0 0)
			(layer "F.SilkS")
			(hide yes)
			(effects
				(font
					(size 1.27 1.27)
				)
			)
		)
		(property "Value" "SC10U25V6KX-1GP"
			(at -0.0762 -5.1308 0)
			(unlocked yes)
			(layer "F.Fab")
			(hide yes)
			(effects
				(font
					(size 1.016 1.016)
					(thickness 0.1524)
				)
			)
		)
		(property "Device Type" "C1206H71"
			(at -0.127 -6.6548 0)
			(unlocked yes)
			(layer "F.Fab")
			(hide yes)
			(effects
				(font
					(size 1.016 1.016)
					(thickness 0.1524)
				)
			)
		)
		(duplicate_pad_numbers_are_jumpers no)
		(fp_line
			(start -1.016 -2.2352)
			(end 1.016 -2.2352)
			(stroke
				(width 0.1524)
				(type default)
			)
			(layer "F.SilkS")
		)
		(fp_line
			(start -1.016 -0.8382)
			(end -1.016 -2.2352)
			(stroke
				(width 0.1524)
				(type default)
			)
			(layer "F.SilkS")
		)
		(fp_line
			(start -1.016 2.2352)
			(end -1.016 0.8382)
			(stroke
				(width 0.1524)
				(type default)
			)
			(layer "F.SilkS")
		)
		(fp_line
			(start 1.016 -2.2352)
			(end 1.016 -0.8382)
			(stroke
				(width 0.1524)
				(type default)
			)
			(layer "F.SilkS")
		)
		(fp_line
			(start 1.016 0.8382)
			(end 1.016 2.2352)
			(stroke
				(width 0.1524)
				(type default)
			)
			(layer "F.SilkS")
		)
		(fp_line
			(start 1.016 2.2352)
			(end -1.016 2.2352)
			(stroke
				(width 0.1524)
				(type default)
			)
			(layer "F.SilkS")
		)
		(fp_rect
			(start -1.0922 2.3114)
			(end 1.0922 -2.3114)
			(stroke
				(width 0)
				(type default)
			)
			(fill no)
			(layer "F.CrtYd")
		)
		(fp_poly
			(pts
				(xy 1.0922 -2.3114) (xy 1.0922 2.3114) (xy -1.0922 2.3114) (xy -1.0922 -2.3114)
			)
			(stroke
				(width 0)
				(type default)
			)
			(fill no)
			(layer "F.Fab")
		)
		(pad "1" smd rect
			(at 0 -1.397)
			(size 1.651 1.27)
			(layers "F.Cu" "F.Mask" "F.Paste")
			(net "P12V_HDD1")
		)
		(pad "2" smd rect
			(at 0 1.397)
			(size 1.651 1.27)
			(layers "F.Cu" "F.Mask" "F.Paste")
			(net "GND")
		)
	)
	(footprint ""
		(layer "F.Cu")
		(at 44.3992 -427.2534)
		(property "Reference" "Q66"
			(at 0 0 0)
			(layer "F.SilkS")
			(hide yes)
			(effects
				(font
					(size 1.27 1.27)
				)
			)
		)
		(property "Value" "2N7002DW-7F-GP"
			(at -2.3622 -8.2042 0)
			(unlocked yes)
			(layer "F.Fab")
			(hide yes)
			(effects
				(font
					(size 1.016 1.016)
					(thickness 0.1524)
				)
			)
		)
		(property "Device Type" "SOT-363H44"
			(at -2.3622 -10.1092 0)
			(unlocked yes)
			(layer "F.Fab")
			(hide yes)
			(effects
				(font
					(size 1.016 1.016)
					(thickness 0.1524)
				)
			)
		)
		(duplicate_pad_numbers_are_jumpers no)
		(fp_line
			(start -1.4478 -1.7018)
			(end -1.4478 1.7018)
			(stroke
				(width 0.1524)
				(type default)
			)
			(layer "F.SilkS")
		)
		(fp_line
			(start -1.4478 1.7018)
			(end 1.4478 1.7018)
			(stroke
				(width 0.1524)
				(type default)
			)
			(layer "F.SilkS")
		)
		(fp_line
			(start -1.27 1.524)
			(end -1.27 0.6604)
			(stroke
				(width 0.4826)
				(type default)
			)
			(layer "F.SilkS")
		)
		(fp_line
			(start 1.4478 -1.7018)
			(end -1.4478 -1.7018)
			(stroke
				(width 0.1524)
				(type default)
			)
			(layer "F.SilkS")
		)
		(fp_line
			(start 1.4478 1.7018)
			(end 1.4478 -1.7018)
			(stroke
				(width 0.1524)
				(type default)
			)
			(layer "F.SilkS")
		)
		(fp_poly
			(pts
				(xy -1.524 -1.778) (xy 1.524 -1.778) (xy 1.524 1.778) (xy -1.524 1.778)
			)
			(stroke
				(width 0)
				(type default)
			)
			(fill no)
			(layer "F.CrtYd")
		)
		(fp_poly
			(pts
				(xy -1.524 -1.778) (xy 1.524 -1.778) (xy 1.524 1.778) (xy -1.524 1.778)
			)
			(stroke
				(width 0)
				(type default)
			)
			(fill no)
			(layer "F.Fab")
		)
		(pad "1" smd rect
			(at -0.65024 0.9398)
			(size 0.4064 1.016)
			(layers "F.Cu" "F.Mask" "F.Paste")
			(net "P3V3_HDD10_LED")
		)
		(pad "2" smd rect
			(at 0 0.9398)
			(size 0.4064 1.016)
			(layers "F.Cu" "F.Mask" "F.Paste")
			(net "HDD10_LED_G")
		)
		(pad "3" smd rect
			(at 0.65024 0.9398)
			(size 0.4064 1.016)
			(layers "F.Cu" "F.Mask" "F.Paste")
			(net "P5VC")
		)
		(pad "4" smd rect
			(at 0.65024 -0.9398)
			(size 0.4064 1.016)
			(layers "F.Cu" "F.Mask" "F.Paste")
			(net "P5VC_HDD10_LED")
		)
		(pad "5" smd rect
			(at 0 -0.9398)
			(size 0.4064 1.016)
			(layers "F.Cu" "F.Mask" "F.Paste")
			(net "HDD10_LED_G")
		)
		(pad "6" smd rect
			(at -0.65024 -0.9398)
			(size 0.4064 1.016)
			(layers "F.Cu" "F.Mask" "F.Paste")
			(net "P3V3")
		)
	)
	(footprint ""
		(layer "F.Cu")
		(at 216.999058 -378.281184)
		(property "Reference" "R125"
			(at 0 0 0)
			(layer "F.SilkS")
			(hide yes)
			(effects
				(font
					(size 1.27 1.27)
				)
			)
		)
		(property "Value" "220R3F-1-GP"
			(at -0.0254 -2.5146 0)
			(unlocked yes)
			(layer "F.Fab")
			(hide yes)
			(effects
				(font
					(size 1.016 1.016)
					(thickness 0.1524)
				)
			)
		)
		(property "Device Type" "R603H22"
			(at -0.0254 -4.0386 0)
			(unlocked yes)
			(layer "F.Fab")
			(hide yes)
			(effects
				(font
					(size 1.016 1.016)
					(thickness 0.1524)
				)
			)
		)
		(duplicate_pad_numbers_are_jumpers no)
		(fp_line
			(start -0.4826 0)
			(end -0.2032 0)
			(stroke
				(width 0.2032)
				(type default)
			)
			(layer "F.SilkS")
		)
		(fp_line
			(start 0.2032 0)
			(end 0.4826 0)
			(stroke
				(width 0.2032)
				(type default)
			)
			(layer "F.SilkS")
		)
		(fp_rect
			(start -0.5842 1.3335)
			(end 0.5842 -1.3335)
			(stroke
				(width 0)
				(type default)
			)
			(fill no)
			(layer "F.CrtYd")
		)
		(fp_rect
			(start -0.5842 1.3335)
			(end 0.5842 -1.3335)
			(stroke
				(width 0)
				(type default)
			)
			(fill no)
			(layer "F.Fab")
		)
		(pad "1" smd custom
			(at 0 -0.762)
			(size 0.2159 0.2159)
			(layers "F.Cu" "F.Mask" "F.Paste")
			(net "HDD_PRSNT_NET1")
			(options
				(clearance outline)
				(anchor circle)
			)
			(primitives
				(gr_poly
					(pts
						(arc
							(start -0.3302 -0.4318)
							(mid -0.402042 -0.402042)
							(end -0.4318 -0.3302)
						)
						(arc
							(start -0.4318 0.3302)
							(mid -0.402042 0.402042)
							(end -0.3302 0.4318)
						)
						(arc
							(start 0.3302 0.4318)
							(mid 0.402042 0.402042)
							(end 0.4318 0.3302)
						)
						(arc
							(start 0.4318 -0.3302)
							(mid 0.402042 -0.402042)
							(end 0.3302 -0.4318)
						)
					)
					(width 0)
					(fill yes)
				)
			)
		)
		(pad "2" smd custom
			(at 0 0.762)
			(size 0.2159 0.2159)
			(layers "F.Cu" "F.Mask" "F.Paste")
			(net "HDD_PRSNT1")
			(options
				(clearance outline)
				(anchor circle)
			)
			(primitives
				(gr_poly
					(pts
						(arc
							(start -0.3302 -0.4318)
							(mid -0.402042 -0.402042)
							(end -0.4318 -0.3302)
						)
						(arc
							(start -0.4318 0.3302)
							(mid -0.402042 0.402042)
							(end -0.3302 0.4318)
						)
						(arc
							(start 0.3302 0.4318)
							(mid 0.402042 0.402042)
							(end 0.4318 0.3302)
						)
						(arc
							(start 0.4318 -0.3302)
							(mid 0.402042 -0.402042)
							(end 0.3302 -0.4318)
						)
					)
					(width 0)
					(fill yes)
				)
			)
		)
	)
	(footprint ""
		(layer "F.Cu")
		(at 195.707 -396.24)
		(property "Reference" "C380"
			(at 0 0 0)
			(layer "F.SilkS")
			(hide yes)
			(effects
				(font
					(size 1.27 1.27)
				)
			)
		)
		(property "Value" "SCD033U25V2KX-GP"
			(at 1.1811 -2.7051 0)
			(unlocked yes)
			(layer "F.Fab")
			(hide yes)
			(effects
				(font
					(size 1.016 1.016)
					(thickness 0.1524)
				)
			)
		)
		(property "Device Type" "C402H22"
			(at 1.1811 -4.2291 0)
			(unlocked yes)
			(layer "F.Fab")
			(hide yes)
			(effects
				(font
					(size 1.016 1.016)
					(thickness 0.1524)
				)
			)
		)
		(duplicate_pad_numbers_are_jumpers no)
		(fp_rect
			(start -0.4318 0.9525)
			(end 0.4318 -0.9525)
			(stroke
				(width 0)
				(type default)
			)
			(fill no)
			(layer "F.CrtYd")
		)
		(fp_rect
			(start -0.4318 0.9525)
			(end 0.4318 -0.9525)
			(stroke
				(width 0)
				(type default)
			)
			(fill no)
			(layer "F.Fab")
		)
		(pad "1" smd custom
			(at 0 -0.4445)
			(size 0.1524 0.1524)
			(layers "F.Cu" "F.Mask" "F.Paste")
			(net "P12V")
			(options
				(clearance outline)
				(anchor circle)
			)
			(primitives
				(gr_poly
					(pts
						(arc
							(start 0.3048 -0.2032)
							(mid 0.275042 -0.275042)
							(end 0.2032 -0.3048)
						)
						(arc
							(start -0.2032 -0.3048)
							(mid -0.275042 -0.275042)
							(end -0.3048 -0.2032)
						)
						(arc
							(start -0.3048 0.2032)
							(mid -0.275042 0.275042)
							(end -0.2032 0.3048)
						)
						(arc
							(start 0.2032 0.3048)
							(mid 0.275042 0.275042)
							(end 0.3048 0.2032)
						)
					)
					(width 0)
					(fill yes)
				)
			)
		)
		(pad "2" smd custom
			(at 0 0.4445)
			(size 0.1524 0.1524)
			(layers "F.Cu" "F.Mask" "F.Paste")
			(net "SW_HDD1_N")
			(options
				(clearance outline)
				(anchor circle)
			)
			(primitives
				(gr_poly
					(pts
						(arc
							(start 0.3048 -0.2032)
							(mid 0.275042 -0.275042)
							(end 0.2032 -0.3048)
						)
						(arc
							(start -0.2032 -0.3048)
							(mid -0.275042 -0.275042)
							(end -0.3048 -0.2032)
						)
						(arc
							(start -0.3048 0.2032)
							(mid -0.275042 0.275042)
							(end -0.2032 0.3048)
						)
						(arc
							(start 0.2032 0.3048)
							(mid 0.275042 0.275042)
							(end 0.3048 0.2032)
						)
					)
					(width 0)
					(fill yes)
				)
			)
		)
	)
)
